(kicad_pcb
	(version 20260206)
	(generator "pcbnew")
	(generator_version "10.0")
	(general
		(thickness 1.6)
		(legacy_teardrops no)
	)
	(paper "A4")
	(title_block
		(title "01162023_DA0F0TEBIF0_F0T_Expander_BD_F_brd_V02_OCP.brd")
		(comment 1 "Grand Teton / footprints 1815-1822 of 9728")
	)
	(layers
		(0 "F.Cu" signal "TOP")
		(4 "In1.Cu" signal "GND")
		(6 "In2.Cu" signal "VCC")
		(8 "In3.Cu" signal "VCC1")
		(10 "In4.Cu" signal "GND1")
		(12 "In5.Cu" signal "IN1")
		(14 "In6.Cu" signal "GND2")
		(16 "In7.Cu" signal "IN2")
		(18 "In8.Cu" signal "GND3")
		(20 "In9.Cu" signal "IN3")
		(22 "In10.Cu" signal "GND4")
		(24 "In11.Cu" signal "IN4")
		(26 "In12.Cu" signal "GND5")
		(28 "In13.Cu" signal "IN5")
		(30 "In14.Cu" signal "GND6")
		(32 "In15.Cu" signal "IN6")
		(34 "In16.Cu" signal "GND7")
		(2 "B.Cu" signal "BOTTOM")
		(9 "F.Adhes" user "F.Adhesive")
		(11 "B.Adhes" user "B.Adhesive")
		(13 "F.Paste" user "Package Geometry/Pastemask Top")
		(15 "B.Paste" user "Package Geometry/Pastemask Bottom")
		(5 "F.SilkS" user "Ref Des/Silkscreen Top")
		(7 "B.SilkS" user "Ref Des/Silkscreen Bottom")
		(1 "F.Mask" user "Board Geometry/Soldermask Top")
		(3 "B.Mask" user "Board Geometry/Soldermask Bottom")
		(17 "Dwgs.User" user "User.Drawings")
		(19 "Cmts.User" user "User.Comments")
		(21 "Eco1.User" user "User.Eco1")
		(23 "Eco2.User" user "User.Eco2")
		(25 "Edge.Cuts" user "Board Geometry/Outline")
		(27 "Margin" user)
		(31 "F.CrtYd" user "Package Geometry/Place Bound Top")
		(29 "B.CrtYd" user "Package Geometry/Place Bound Bottom")
		(35 "F.Fab" user "Ref Des/Assembly Top")
		(33 "B.Fab" user "Ref Des/Assembly Bottom")
	)
	(footprint ""
		(layer "F.Cu")
		(at 225.711512 -231.416606 -90)
		(property "Reference" "R4542"
			(at 0 0 270)
			(layer "F.SilkS")
			(hide yes)
			(effects
				(font
					(size 1.27 1.27)
				)
			)
		)
		(property "Value" ""
			(at 0 0 270)
			(layer "F.Fab")
			(effects
				(font
					(size 1.27 1.27)
				)
			)
		)
		(duplicate_pad_numbers_are_jumpers no)
		(fp_line
			(start -0.7874 0.4064)
			(end -0.7874 -0.4064)
			(stroke
				(width 0.1524)
				(type default)
			)
			(layer "F.SilkS")
		)
		(fp_line
			(start 0.7874 0.4064)
			(end -0.7874 0.4064)
			(stroke
				(width 0.1524)
				(type default)
			)
			(layer "F.SilkS")
		)
		(fp_line
			(start -0.7874 -0.4064)
			(end 0.7874 -0.4064)
			(stroke
				(width 0.1524)
				(type default)
			)
			(layer "F.SilkS")
		)
		(fp_line
			(start 0.7874 -0.4064)
			(end 0.7874 0.4064)
			(stroke
				(width 0.1524)
				(type default)
			)
			(layer "F.SilkS")
		)
		(fp_line
			(start -0.67945 0.3048)
			(end -0.67945 -0.305054)
			(stroke
				(width 0.1)
				(type default)
			)
			(layer "F.Fab")
		)
		(fp_line
			(start -0.12065 0.3048)
			(end -0.67945 0.3048)
			(stroke
				(width 0.1)
				(type default)
			)
			(layer "F.Fab")
		)
		(fp_line
			(start 0.120396 0.3048)
			(end 0.120396 0.2794)
			(stroke
				(width 0.1)
				(type default)
			)
			(layer "F.Fab")
		)
		(fp_line
			(start 0.67945 0.3048)
			(end 0.120396 0.3048)
			(stroke
				(width 0.1)
				(type default)
			)
			(layer "F.Fab")
		)
		(fp_line
			(start -0.12065 0.2794)
			(end -0.12065 0.3048)
			(stroke
				(width 0.1)
				(type default)
			)
			(layer "F.Fab")
		)
		(fp_line
			(start 0.120396 0.2794)
			(end -0.12065 0.2794)
			(stroke
				(width 0.1)
				(type default)
			)
			(layer "F.Fab")
		)
		(fp_line
			(start -0.12065 -0.2794)
			(end 0.12065 -0.2794)
			(stroke
				(width 0.1)
				(type default)
			)
			(layer "F.Fab")
		)
		(fp_line
			(start 0.12065 -0.2794)
			(end 0.12065 -0.3048)
			(stroke
				(width 0.1)
				(type default)
			)
			(layer "F.Fab")
		)
		(fp_line
			(start 0.12065 -0.3048)
			(end 0.67945 -0.3048)
			(stroke
				(width 0.1)
				(type default)
			)
			(layer "F.Fab")
		)
		(fp_line
			(start 0.67945 -0.3048)
			(end 0.67945 0.3048)
			(stroke
				(width 0.1)
				(type default)
			)
			(layer "F.Fab")
		)
		(fp_line
			(start -0.67945 -0.305054)
			(end -0.12065 -0.305054)
			(stroke
				(width 0.1)
				(type default)
			)
			(layer "F.Fab")
		)
		(fp_line
			(start -0.12065 -0.305054)
			(end -0.12065 -0.2794)
			(stroke
				(width 0.1)
				(type default)
			)
			(layer "F.Fab")
		)
		(pad "1" smd circle
			(at -0.40005 0 270)
			(size 0 0)
			(layers "F.Cu" "F.Mask" "F.Paste")
			(net "NIC6_MAIN_PWR_BIC_EN_R")
		)
		(pad "2" smd circle
			(at 0.40005 0 270)
			(size 0 0)
			(layers "F.Cu" "F.Mask" "F.Paste")
			(net "NIC6_MAIN_PWR_BIC_EN")
		)
	)
	(footprint ""
		(layer "F.Cu")
		(at 441.273692 -350.098614 90)
		(property "Reference" "C2470"
			(at 0 0 90)
			(layer "F.SilkS")
			(hide yes)
			(effects
				(font
					(size 1.27 1.27)
				)
			)
		)
		(property "Value" ""
			(at 0 0 90)
			(layer "F.Fab")
			(effects
				(font
					(size 1.27 1.27)
				)
			)
		)
		(duplicate_pad_numbers_are_jumpers no)
		(fp_line
			(start 0.299974 -0.150114)
			(end 0.299974 0.150114)
			(stroke
				(width 0.1)
				(type default)
			)
			(layer "F.Fab")
		)
		(fp_line
			(start -0.299974 -0.150114)
			(end 0.299974 -0.150114)
			(stroke
				(width 0.1)
				(type default)
			)
			(layer "F.Fab")
		)
		(fp_line
			(start 0.299974 0.150114)
			(end -0.299974 0.150114)
			(stroke
				(width 0.1)
				(type default)
			)
			(layer "F.Fab")
		)
		(fp_line
			(start -0.299974 0.150114)
			(end -0.299974 -0.150114)
			(stroke
				(width 0.1)
				(type default)
			)
			(layer "F.Fab")
		)
		(pad "1" smd rect
			(at -0.2667 0 90)
			(size 0.3048 0.381)
			(layers "F.Cu" "F.Mask" "F.Paste")
			(net "P5E_PEX3_STN4_TX_DN<64>")
		)
		(pad "2" smd rect
			(at 0.2667 0 90)
			(size 0.3048 0.381)
			(layers "F.Cu" "F.Mask" "F.Paste")
			(net "P5E_PEX3_STN4_TX_C_DN<64>")
		)
	)
	(footprint ""
		(layer "F.Cu")
		(at 211.892388 -31.825184 180)
		(property "Reference" "C303"
			(at 0 0 180)
			(layer "F.SilkS")
			(hide yes)
			(effects
				(font
					(size 1.27 1.27)
				)
			)
		)
		(property "Value" ""
			(at 0 0 180)
			(layer "F.Fab")
			(effects
				(font
					(size 1.27 1.27)
				)
			)
		)
		(duplicate_pad_numbers_are_jumpers no)
		(fp_line
			(start 0.299974 0.150114)
			(end -0.299974 0.150114)
			(stroke
				(width 0.1)
				(type default)
			)
			(layer "F.Fab")
		)
		(fp_line
			(start 0.299974 -0.150114)
			(end 0.299974 0.150114)
			(stroke
				(width 0.1)
				(type default)
			)
			(layer "F.Fab")
		)
		(fp_line
			(start -0.299974 0.150114)
			(end -0.299974 -0.150114)
			(stroke
				(width 0.1)
				(type default)
			)
			(layer "F.Fab")
		)
		(fp_line
			(start -0.299974 -0.150114)
			(end 0.299974 -0.150114)
			(stroke
				(width 0.1)
				(type default)
			)
			(layer "F.Fab")
		)
		(pad "1" smd rect
			(at -0.2667 0 180)
			(size 0.3048 0.381)
			(layers "F.Cu" "F.Mask" "F.Paste")
			(net "P5E_PEX1_STN2_TX_DN<34>")
		)
		(pad "2" smd rect
			(at 0.2667 0 180)
			(size 0.3048 0.381)
			(layers "F.Cu" "F.Mask" "F.Paste")
			(net "P5E_PEX1_STN2_TX_C_DN<34>")
		)
	)
	(footprint ""
		(layer "F.Cu")
		(at 233.326178 -37.929566 90)
		(property "Reference" "R5564"
			(at 0 0 90)
			(layer "F.SilkS")
			(hide yes)
			(effects
				(font
					(size 1.27 1.27)
				)
			)
		)
		(property "Value" ""
			(at 0 0 90)
			(layer "F.Fab")
			(effects
				(font
					(size 1.27 1.27)
				)
			)
		)
		(duplicate_pad_numbers_are_jumpers no)
		(fp_line
			(start 0.7874 -0.4064)
			(end 0.7874 0.4064)
			(stroke
				(width 0.1524)
				(type default)
			)
			(layer "F.SilkS")
		)
		(fp_line
			(start -0.7874 -0.4064)
			(end 0.7874 -0.4064)
			(stroke
				(width 0.1524)
				(type default)
			)
			(layer "F.SilkS")
		)
		(fp_line
			(start 0.7874 0.4064)
			(end -0.7874 0.4064)
			(stroke
				(width 0.1524)
				(type default)
			)
			(layer "F.SilkS")
		)
		(fp_line
			(start -0.7874 0.4064)
			(end -0.7874 -0.4064)
			(stroke
				(width 0.1524)
				(type default)
			)
			(layer "F.SilkS")
		)
		(fp_line
			(start -0.12065 -0.305054)
			(end -0.12065 -0.2794)
			(stroke
				(width 0.1)
				(type default)
			)
			(layer "F.Fab")
		)
		(fp_line
			(start -0.67945 -0.305054)
			(end -0.12065 -0.305054)
			(stroke
				(width 0.1)
				(type default)
			)
			(layer "F.Fab")
		)
		(fp_line
			(start 0.67945 -0.3048)
			(end 0.67945 0.3048)
			(stroke
				(width 0.1)
				(type default)
			)
			(layer "F.Fab")
		)
		(fp_line
			(start 0.12065 -0.3048)
			(end 0.67945 -0.3048)
			(stroke
				(width 0.1)
				(type default)
			)
			(layer "F.Fab")
		)
		(fp_line
			(start 0.12065 -0.2794)
			(end 0.12065 -0.3048)
			(stroke
				(width 0.1)
				(type default)
			)
			(layer "F.Fab")
		)
		(fp_line
			(start -0.12065 -0.2794)
			(end 0.12065 -0.2794)
			(stroke
				(width 0.1)
				(type default)
			)
			(layer "F.Fab")
		)
		(fp_line
			(start 0.120396 0.2794)
			(end -0.12065 0.2794)
			(stroke
				(width 0.1)
				(type default)
			)
			(layer "F.Fab")
		)
		(fp_line
			(start -0.12065 0.2794)
			(end -0.12065 0.3048)
			(stroke
				(width 0.1)
				(type default)
			)
			(layer "F.Fab")
		)
		(fp_line
			(start 0.67945 0.3048)
			(end 0.120396 0.3048)
			(stroke
				(width 0.1)
				(type default)
			)
			(layer "F.Fab")
		)
		(fp_line
			(start 0.120396 0.3048)
			(end 0.120396 0.2794)
			(stroke
				(width 0.1)
				(type default)
			)
			(layer "F.Fab")
		)
		(fp_line
			(start -0.12065 0.3048)
			(end -0.67945 0.3048)
			(stroke
				(width 0.1)
				(type default)
			)
			(layer "F.Fab")
		)
		(fp_line
			(start -0.67945 0.3048)
			(end -0.67945 -0.305054)
			(stroke
				(width 0.1)
				(type default)
			)
			(layer "F.Fab")
		)
		(pad "1" smd circle
			(at -0.40005 0 90)
			(size 0 0)
			(layers "F.Cu" "F.Mask" "F.Paste")
			(net "SSD8_AUX_P3V3_EN_R")
		)
		(pad "2" smd circle
			(at 0.40005 0 90)
			(size 0 0)
			(layers "F.Cu" "F.Mask" "F.Paste")
			(net "SSD8_AUX_P3V3_EN")
		)
	)
	(footprint ""
		(layer "F.Cu")
		(at 89.012268 -300.64202 -90)
		(property "Reference" "R3883"
			(at 0 0 270)
			(layer "F.SilkS")
			(hide yes)
			(effects
				(font
					(size 1.27 1.27)
				)
			)
		)
		(property "Value" ""
			(at 0 0 270)
			(layer "F.Fab")
			(effects
				(font
					(size 1.27 1.27)
				)
			)
		)
		(duplicate_pad_numbers_are_jumpers no)
		(fp_line
			(start -0.7874 0.4064)
			(end -0.7874 -0.4064)
			(stroke
				(width 0.1524)
				(type default)
			)
			(layer "F.SilkS")
		)
		(fp_line
			(start 0.7874 0.4064)
			(end -0.7874 0.4064)
			(stroke
				(width 0.1524)
				(type default)
			)
			(layer "F.SilkS")
		)
		(fp_line
			(start -0.7874 -0.4064)
			(end 0.7874 -0.4064)
			(stroke
				(width 0.1524)
				(type default)
			)
			(layer "F.SilkS")
		)
		(fp_line
			(start 0.7874 -0.4064)
			(end 0.7874 0.4064)
			(stroke
				(width 0.1524)
				(type default)
			)
			(layer "F.SilkS")
		)
		(fp_line
			(start -0.67945 0.3048)
			(end -0.67945 -0.305054)
			(stroke
				(width 0.1)
				(type default)
			)
			(layer "F.Fab")
		)
		(fp_line
			(start -0.12065 0.3048)
			(end -0.67945 0.3048)
			(stroke
				(width 0.1)
				(type default)
			)
			(layer "F.Fab")
		)
		(fp_line
			(start 0.120396 0.3048)
			(end 0.120396 0.2794)
			(stroke
				(width 0.1)
				(type default)
			)
			(layer "F.Fab")
		)
		(fp_line
			(start 0.67945 0.3048)
			(end 0.120396 0.3048)
			(stroke
				(width 0.1)
				(type default)
			)
			(layer "F.Fab")
		)
		(fp_line
			(start -0.12065 0.2794)
			(end -0.12065 0.3048)
			(stroke
				(width 0.1)
				(type default)
			)
			(layer "F.Fab")
		)
		(fp_line
			(start 0.120396 0.2794)
			(end -0.12065 0.2794)
			(stroke
				(width 0.1)
				(type default)
			)
			(layer "F.Fab")
		)
		(fp_line
			(start -0.12065 -0.2794)
			(end 0.12065 -0.2794)
			(stroke
				(width 0.1)
				(type default)
			)
			(layer "F.Fab")
		)
		(fp_line
			(start 0.12065 -0.2794)
			(end 0.12065 -0.3048)
			(stroke
				(width 0.1)
				(type default)
			)
			(layer "F.Fab")
		)
		(fp_line
			(start 0.12065 -0.3048)
			(end 0.67945 -0.3048)
			(stroke
				(width 0.1)
				(type default)
			)
			(layer "F.Fab")
		)
		(fp_line
			(start 0.67945 -0.3048)
			(end 0.67945 0.3048)
			(stroke
				(width 0.1)
				(type default)
			)
			(layer "F.Fab")
		)
		(fp_line
			(start -0.67945 -0.305054)
			(end -0.12065 -0.305054)
			(stroke
				(width 0.1)
				(type default)
			)
			(layer "F.Fab")
		)
		(fp_line
			(start -0.12065 -0.305054)
			(end -0.12065 -0.2794)
			(stroke
				(width 0.1)
				(type default)
			)
			(layer "F.Fab")
		)
		(pad "1" smd circle
			(at -0.40005 0 270)
			(size 0 0)
			(layers "F.Cu" "F.Mask" "F.Paste")
			(net "I2C0_PEX0_SHPC_SDA")
		)
		(pad "2" smd circle
			(at 0.40005 0 270)
			(size 0 0)
			(layers "F.Cu" "F.Mask" "F.Paste")
			(net "I2C_PEX0_HOST_SDA")
		)
	)
	(footprint ""
		(layer "F.Cu")
		(at 462.465674 -278.67483)
		(property "Reference" "R801"
			(at 0 0 0)
			(layer "F.SilkS")
			(hide yes)
			(effects
				(font
					(size 1.27 1.27)
				)
			)
		)
		(property "Value" ""
			(at 0 0 0)
			(layer "F.Fab")
			(effects
				(font
					(size 1.27 1.27)
				)
			)
		)
		(duplicate_pad_numbers_are_jumpers no)
		(fp_line
			(start -0.7874 -0.4064)
			(end 0.7874 -0.4064)
			(stroke
				(width 0.1524)
				(type default)
			)
			(layer "F.SilkS")
		)
		(fp_line
			(start -0.7874 0.4064)
			(end -0.7874 -0.4064)
			(stroke
				(width 0.1524)
				(type default)
			)
			(layer "F.SilkS")
		)
		(fp_line
			(start 0.7874 -0.4064)
			(end 0.7874 0.4064)
			(stroke
				(width 0.1524)
				(type default)
			)
			(layer "F.SilkS")
		)
		(fp_line
			(start 0.7874 0.4064)
			(end -0.7874 0.4064)
			(stroke
				(width 0.1524)
				(type default)
			)
			(layer "F.SilkS")
		)
		(fp_line
			(start -0.67945 -0.305054)
			(end -0.12065 -0.305054)
			(stroke
				(width 0.1)
				(type default)
			)
			(layer "F.Fab")
		)
		(fp_line
			(start -0.67945 0.3048)
			(end -0.67945 -0.305054)
			(stroke
				(width 0.1)
				(type default)
			)
			(layer "F.Fab")
		)
		(fp_line
			(start -0.12065 -0.305054)
			(end -0.12065 -0.2794)
			(stroke
				(width 0.1)
				(type default)
			)
			(layer "F.Fab")
		)
		(fp_line
			(start -0.12065 -0.2794)
			(end 0.12065 -0.2794)
			(stroke
				(width 0.1)
				(type default)
			)
			(layer "F.Fab")
		)
		(fp_line
			(start -0.12065 0.2794)
			(end -0.12065 0.3048)
			(stroke
				(width 0.1)
				(type default)
			)
			(layer "F.Fab")
		)
		(fp_line
			(start -0.12065 0.3048)
			(end -0.67945 0.3048)
			(stroke
				(width 0.1)
				(type default)
			)
			(layer "F.Fab")
		)
		(fp_line
			(start 0.120396 0.2794)
			(end -0.12065 0.2794)
			(stroke
				(width 0.1)
				(type default)
			)
			(layer "F.Fab")
		)
		(fp_line
			(start 0.120396 0.3048)
			(end 0.120396 0.2794)
			(stroke
				(width 0.1)
				(type default)
			)
			(layer "F.Fab")
		)
		(fp_line
			(start 0.12065 -0.3048)
			(end 0.67945 -0.3048)
			(stroke
				(width 0.1)
				(type default)
			)
			(layer "F.Fab")
		)
		(fp_line
			(start 0.12065 -0.2794)
			(end 0.12065 -0.3048)
			(stroke
				(width 0.1)
				(type default)
			)
			(layer "F.Fab")
		)
		(fp_line
			(start 0.67945 -0.3048)
			(end 0.67945 0.3048)
			(stroke
				(width 0.1)
				(type default)
			)
			(layer "F.Fab")
		)
		(fp_line
			(start 0.67945 0.3048)
			(end 0.120396 0.3048)
			(stroke
				(width 0.1)
				(type default)
			)
			(layer "F.Fab")
		)
		(pad "1" smd circle
			(at -0.40005 0)
			(size 0 0)
			(layers "F.Cu" "F.Mask" "F.Paste")
			(net "P3V3_AUX")
		)
		(pad "2" smd circle
			(at 0.40005 0)
			(size 0 0)
			(layers "F.Cu" "F.Mask" "F.Paste")
			(net "PEX_ADC_ALERT_N")
		)
	)
	(footprint ""
		(layer "F.Cu")
		(at 378.079 -203.2 90)
		(property "Reference" "C3600"
			(at 0 0 90)
			(layer "F.SilkS")
			(hide yes)
			(effects
				(font
					(size 1.27 1.27)
				)
			)
		)
		(property "Value" ""
			(at 0 0 90)
			(layer "F.Fab")
			(effects
				(font
					(size 1.27 1.27)
				)
			)
		)
		(duplicate_pad_numbers_are_jumpers no)
		(fp_line
			(start 0.7874 -0.4064)
			(end 0.7874 0.4064)
			(stroke
				(width 0.1524)
				(type default)
			)
			(layer "F.SilkS")
		)
		(fp_line
			(start -0.7874 -0.4064)
			(end 0.7874 -0.4064)
			(stroke
				(width 0.1524)
				(type default)
			)
			(layer "F.SilkS")
		)
		(fp_line
			(start 0.7874 0.4064)
			(end -0.7874 0.4064)
			(stroke
				(width 0.1524)
				(type default)
			)
			(layer "F.SilkS")
		)
		(fp_line
			(start -0.7874 0.4064)
			(end -0.7874 -0.4064)
			(stroke
				(width 0.1524)
				(type default)
			)
			(layer "F.SilkS")
		)
		(fp_line
			(start -0.12065 -0.305054)
			(end -0.12065 -0.2794)
			(stroke
				(width 0.1)
				(type default)
			)
			(layer "F.Fab")
		)
		(fp_line
			(start -0.67945 -0.305054)
			(end -0.12065 -0.305054)
			(stroke
				(width 0.1)
				(type default)
			)
			(layer "F.Fab")
		)
		(fp_line
			(start 0.67945 -0.3048)
			(end 0.67945 0.3048)
			(stroke
				(width 0.1)
				(type default)
			)
			(layer "F.Fab")
		)
		(fp_line
			(start 0.12065 -0.3048)
			(end 0.67945 -0.3048)
			(stroke
				(width 0.1)
				(type default)
			)
			(layer "F.Fab")
		)
		(fp_line
			(start 0.12065 -0.2794)
			(end 0.12065 -0.3048)
			(stroke
				(width 0.1)
				(type default)
			)
			(layer "F.Fab")
		)
		(fp_line
			(start -0.12065 -0.2794)
			(end 0.12065 -0.2794)
			(stroke
				(width 0.1)
				(type default)
			)
			(layer "F.Fab")
		)
		(fp_line
			(start 0.120396 0.2794)
			(end -0.12065 0.2794)
			(stroke
				(width 0.1)
				(type default)
			)
			(layer "F.Fab")
		)
		(fp_line
			(start -0.12065 0.2794)
			(end -0.12065 0.3048)
			(stroke
				(width 0.1)
				(type default)
			)
			(layer "F.Fab")
		)
		(fp_line
			(start 0.67945 0.3048)
			(end 0.120396 0.3048)
			(stroke
				(width 0.1)
				(type default)
			)
			(layer "F.Fab")
		)
		(fp_line
			(start 0.120396 0.3048)
			(end 0.120396 0.2794)
			(stroke
				(width 0.1)
				(type default)
			)
			(layer "F.Fab")
		)
		(fp_line
			(start -0.12065 0.3048)
			(end -0.67945 0.3048)
			(stroke
				(width 0.1)
				(type default)
			)
			(layer "F.Fab")
		)
		(fp_line
			(start -0.67945 0.3048)
			(end -0.67945 -0.305054)
			(stroke
				(width 0.1)
				(type default)
			)
			(layer "F.Fab")
		)
		(pad "1" smd circle
			(at -0.40005 0 90)
			(size 0 0)
			(layers "F.Cu" "F.Mask" "F.Paste")
			(net "P3V3_AUX")
		)
		(pad "2" smd circle
			(at 0.40005 0 90)
			(size 0 0)
			(layers "F.Cu" "F.Mask" "F.Paste")
			(net "GND")
		)
	)
	(footprint ""
		(layer "F.Cu")
		(at 284.330902 -350.098614 90)
		(property "Reference" "C2356"
			(at 0 0 90)
			(layer "F.SilkS")
			(hide yes)
			(effects
				(font
					(size 1.27 1.27)
				)
			)
		)
		(property "Value" ""
			(at 0 0 90)
			(layer "F.Fab")
			(effects
				(font
					(size 1.27 1.27)
				)
			)
		)
		(duplicate_pad_numbers_are_jumpers no)
		(fp_line
			(start 0.299974 -0.150114)
			(end 0.299974 0.150114)
			(stroke
				(width 0.1)
				(type default)
			)
			(layer "F.Fab")
		)
		(fp_line
			(start -0.299974 -0.150114)
			(end 0.299974 -0.150114)
			(stroke
				(width 0.1)
				(type default)
			)
			(layer "F.Fab")
		)
		(fp_line
			(start 0.299974 0.150114)
			(end -0.299974 0.150114)
			(stroke
				(width 0.1)
				(type default)
			)
			(layer "F.Fab")
		)
		(fp_line
			(start -0.299974 0.150114)
			(end -0.299974 -0.150114)
			(stroke
				(width 0.1)
				(type default)
			)
			(layer "F.Fab")
		)
		(pad "1" smd rect
			(at -0.2667 0 90)
			(size 0.3048 0.381)
			(layers "F.Cu" "F.Mask" "F.Paste")
			(net "P5E_PEX2_STN4_TX_DN<72>")
		)
		(pad "2" smd rect
			(at 0.2667 0 90)
			(size 0.3048 0.381)
			(layers "F.Cu" "F.Mask" "F.Paste")
			(net "P5E_PEX2_STN4_TX_C_DN<72>")
		)
	)
)
